#ISCELL
  mstr_misc dns *
  *
#ISCELL
  pure_quanta quanta_title_block_c *
  *
#ISCELL
  pure_quanta_power universal_gnd *
  page177_i1
#CELL
  pure_quanta q_cap *
  page177_i100
#CELL
  pure_quanta q_cap *
  page177_i101
#CELL
  pure_quanta q_res *
  page177_i102
#CELL
  pure_quanta q_cap *
  page177_i103
#CELL
  pure_quanta q_res *
  page177_i104
#CELL
  pure_quanta q_cap *
  page177_i105
#CELL
  pure_quanta q_cap *
  page177_i106
#CELL
  pure_quanta q_cap *
  page177_i107
#ISCELL
  pure_quanta_power universal_gnd *
  page177_i108
#ISCELL
  pure_quanta_power universal_gnd *
  page177_i109
#ISCELL
  pure_quanta_power universal_gnd *
  page177_i11
#CELL
  pure_quanta q_res *
  page177_i110
#CELL
  pure_quanta q_cap *
  page177_i111
#CELL
  pure_quanta q_cap *
  page177_i113
#ISCELL
  pure_quanta_power universal_gnd *
  page177_i114
#ISCELL
  pure_quanta_power universal_gnd *
  page177_i115
#CELL
  pure_quanta q_res *
  page177_i116
#CELL
  pure_quanta q_cap *
  page177_i117
#ISCELL
  pure_quanta_power universal_gnd *
  page177_i119
#ISCELL
  pure_quanta_power universal_gnd *
  page177_i120
#CELL
  pure_quanta q_cap *
  page177_i121
#CELL
  pure_quanta q_res *
  page177_i122
#ISCELL
  pure_quanta_power universal_gnd *
  page177_i123
#CELL
  pure_quanta q_cap *
  page177_i124
#CELL
  pure_quanta q_res *
  page177_i125
#ISCELL
  pure_quanta_power universal_gnd *
  page177_i126
#ISCELL
  pure_quanta_power universal_gnd *
  page177_i127
#ISCELL
  pure_quanta_power vcc_core *
  page177_i128
#ISCELL
  pure_quanta_power vcc_core *
  page177_i129
#CELL
  pure_quanta isl99390frztr5935 *
  page177_i14
#ISCELL
  pure_quanta_power universal_gnd *
  page177_i15
#ISCELL
  pure_quanta_power universal_gnd *
  page177_i18
#CELL
  pure_quanta q_res *
  page177_i19
#CELL
  pure_quanta q_res *
  page177_i2
#ISCELL
  standard offpage *
  page177_i21
#ISCELL
  standard offpage *
  page177_i22
#ISCELL
  standard offpage *
  page177_i23
#ISCELL
  standard offpage *
  page177_i24
#CELL
  pure_quanta isl99390frztr5935 *
  page177_i30
#CELL
  pure_quanta q_cap *
  page177_i37
#CELL
  pure_quanta q_cap *
  page177_i38
#ISCELL
  standard offpage *
  page177_i4
#CELL
  pure_quanta q_cap *
  page177_i40
#ISCELL
  pure_quanta_power universal_gnd *
  page177_i41
#CELL
  pure_quanta q_cap *
  page177_i42
#ISCELL
  pure_quanta_power vcc_core *
  page177_i43
#ISCELL
  standard offpage *
  page177_i5
#CELL
  pure_quanta q_cap *
  page177_i50
#CELL
  pure_quanta q_cap *
  page177_i51
#CELL
  pure_quanta q_cap *
  page177_i55
#CELL
  pure_quanta q_cap *
  page177_i56
#ISCELL
  pure_quanta_power universal_gnd *
  page177_i57
#ISCELL
  pure_quanta_power vcc_core *
  page177_i58
#ISCELL
  standard offpage *
  page177_i6
#ISCELL
  standard offpage *
  page177_i7
#ISCELL
  standard offpage *
  page177_i73
#ISCELL
  standard offpage *
  page177_i75
#CELL
  pure_quanta q_res *
  page177_i76
#ISCELL
  pure_quanta_power vcc_core *
  page177_i77
#CELL
  pure_quanta q_cap *
  page177_i78
#CELL
  pure_quanta q_cap *
  page177_i79
#ISCELL
  pure_quanta_power universal_gnd *
  page177_i80
#ISCELL
  standard offpage *
  page177_i91
#CELL
  pure_quanta q_res *
  page177_i92
#ISCELL
  pure_quanta_power vcc_core *
  page177_i93
#ISCELL
  pure_quanta_power universal_gnd *
  page177_i94
#CELL
  pure_quanta q_cap *
  page177_i95
#CELL
  pure_quanta q_cap *
  page177_i96
#CELL
  pure_quanta q_inductor4p_14 *
  page177_i97
#CELL
  pure_quanta q_inductor4p_14 *
  page177_i98
#CELL
  pure_quanta q_cap *
  page177_i99
